# S9S_MB_2U (Grand Teton) — schematic netlist excerpt (pin names and nets, part order shuffled) for the footprints in the layout excerpt that follows; sources: Cadence DE-HDL packaged netlist, KiCad conversion of 03242023_DA0F0TMBIJ0_F0T_Motherboard_J_brd_V01_OCP.brd

JP9  CONN3_210HP1030BR1  CONN3_210-HP1-030BR1 EMPTY  pkg HEADER1X3XG  page 183
  \1\  = SMB_SML1_PMBUS_3V3AUX_PCH_SCL_1
  \2\  = GND
  \3\  = SMB_SML1_PMBUS_3V3AUX_PCH_SDA_1

R1203  Q_RES  1K 1% CHIP  pkg 0402LF  page 185 : A = P3V_BAT ; B = P3V_BAT_R

(kicad_pcb
	(version 20260206)
	(generator "pcbnew")
	(generator_version "10.0")
	(general
		(thickness 1.6)
		(legacy_teardrops no)
	)
	(paper "A4")
	(title_block
		(title "03242023_DA0F0TMBIJ0_F0T_Motherboard_J_brd_V01_OCP.brd")
		(comment 1 "Grand Teton / footprints 1800-1801 of 6105")
	)
	(layers
		(0 "F.Cu" signal "TOP")
		(4 "In1.Cu" signal "GND")
		(6 "In2.Cu" signal "IN1")
		(8 "In3.Cu" signal "GND1")
		(10 "In4.Cu" signal "IN2")
		(12 "In5.Cu" signal "GND2")
		(14 "In6.Cu" signal "IN3")
		(16 "In7.Cu" signal "GND3")
		(18 "In8.Cu" signal "VCC")
		(20 "In9.Cu" signal "VCC1")
		(22 "In10.Cu" signal "GND4")
		(24 "In11.Cu" signal "IN4")
		(26 "In12.Cu" signal "GND5")
		(28 "In13.Cu" signal "IN5")
		(30 "In14.Cu" signal "GND6")
		(32 "In15.Cu" signal "IN6")
		(34 "In16.Cu" signal "GND7")
		(2 "B.Cu" signal "BOTTOM")
		(9 "F.Adhes" user "F.Adhesive")
		(11 "B.Adhes" user "B.Adhesive")
		(13 "F.Paste" user "Package Geometry/Pastemask Top")
		(15 "B.Paste" user "Package Geometry/Pastemask Bottom")
		(5 "F.SilkS" user "Ref Des/Silkscreen Top")
		(7 "B.SilkS" user "Ref Des/Silkscreen Bottom")
		(1 "F.Mask" user "Board Geometry/Soldermask Top")
		(3 "B.Mask" user "Board Geometry/Soldermask Bottom")
		(17 "Dwgs.User" user "User.Drawings")
		(19 "Cmts.User" user "User.Comments")
		(21 "Eco1.User" user "User.Eco1")
		(23 "Eco2.User" user "User.Eco2")
		(25 "Edge.Cuts" user "Board Geometry/Outline")
		(27 "Margin" user)
		(31 "F.CrtYd" user "Package Geometry/Place Bound Top")
		(29 "B.CrtYd" user "Package Geometry/Place Bound Bottom")
		(35 "F.Fab" user "Ref Des/Assembly Top")
		(33 "B.Fab" user "Ref Des/Assembly Bottom")
	)
	(footprint ""
		(layer "F.Cu")
		(at 268.28115 -41.435274)
		(property "Reference" "JP9"
			(at -1.4097 -2.009648 0)
			(unlocked yes)
			(layer "F.SilkS")
			(effects
				(font
					(size 0.7874 0.5842)
					(thickness 0.1524)
				)
				(justify left)
			)
		)
		(property "Value" ""
			(at 0 0 0)
			(layer "F.Fab")
			(effects
				(font
					(size 1.27 1.27)
				)
			)
		)
		(duplicate_pad_numbers_are_jumpers no)
		(fp_line
			(start -1.249934 -1.320038)
			(end 1.249934 -1.320038)
			(stroke
				(width 0.1524)
				(type default)
			)
			(layer "F.SilkS")
		)
		(fp_line
			(start -1.249934 6.400038)
			(end -1.249934 -1.320038)
			(stroke
				(width 0.1524)
				(type default)
			)
			(layer "F.SilkS")
		)
		(fp_line
			(start 1.249934 -1.320038)
			(end 1.249934 6.400038)
			(stroke
				(width 0.1524)
				(type default)
			)
			(layer "F.SilkS")
		)
		(fp_line
			(start 1.249934 6.400038)
			(end -1.249934 6.400038)
			(stroke
				(width 0.1524)
				(type default)
			)
			(layer "F.SilkS")
		)
		(fp_poly
			(pts
				(xy -1.406652 0) (xy -2.13741 0.365506) (xy -2.13741 -0.365506)
			)
			(stroke
				(width 0)
				(type default)
			)
			(fill yes)
			(layer "F.SilkS")
		)
		(fp_line
			(start -1.249934 -1.320038)
			(end 1.249934 -1.320038)
			(stroke
				(width 0.1)
				(type default)
			)
			(layer "F.Fab")
		)
		(fp_line
			(start -1.249934 6.400038)
			(end -1.249934 -1.320038)
			(stroke
				(width 0.1)
				(type default)
			)
			(layer "F.Fab")
		)
		(fp_line
			(start 1.249934 -1.320038)
			(end 1.249934 6.400038)
			(stroke
				(width 0.1)
				(type default)
			)
			(layer "F.Fab")
		)
		(fp_line
			(start 1.249934 6.400038)
			(end -1.249934 6.400038)
			(stroke
				(width 0.1)
				(type default)
			)
			(layer "F.Fab")
		)
		(fp_poly
			(pts
				(xy -2.5654 -0.556514) (xy -1.452372 0) (xy -2.5654 0.556514)
			)
			(stroke
				(width 0)
				(type default)
			)
			(fill yes)
			(layer "F.Fab")
		)
		(fp_text user "3"
			(at -1.778 5.13207 0)
			(unlocked yes)
			(layer "F.SilkS")
			(effects
				(font
					(size 0.7874 0.5842)
					(thickness 0.1524)
				)
			)
		)
		(fp_text user "3"
			(at -1.1557 5.18287 0)
			(unlocked yes)
			(layer "B.SilkS")
			(effects
				(font
					(size 0.7874 0.5842)
					(thickness 0.1524)
				)
				(justify mirror)
			)
		)
		(fp_text user "1"
			(at -1.143 0.02667 0)
			(unlocked yes)
			(layer "B.SilkS")
			(effects
				(font
					(size 0.7874 0.5842)
					(thickness 0.1524)
				)
				(justify mirror)
			)
		)
		(fp_text user "3"
			(at -1.1557 5.18287 0)
			(unlocked yes)
			(layer "B.Fab")
			(effects
				(font
					(size 0.7874 0.5842)
					(thickness 0.1524)
				)
				(justify mirror)
			)
		)
		(fp_text user "1"
			(at -1.143 0.02667 0)
			(unlocked yes)
			(layer "B.Fab")
			(effects
				(font
					(size 0.7874 0.5842)
					(thickness 0.1524)
				)
				(justify mirror)
			)
		)
		(fp_text user "3"
			(at -1.778 5.13207 0)
			(unlocked yes)
			(layer "F.Fab")
			(effects
				(font
					(size 0.7874 0.5842)
					(thickness 0.1524)
				)
			)
		)
		(pad "1" thru_hole rect
			(at 0 0)
			(size 1.5494 1.5494)
			(drill 1.0414)
			(layers "*.Cu" "*.Mask")
			(remove_unused_layers no)
			(net "SMB_SML1_PMBUS_3V3AUX_PCH_SCL_1")
			(clearance 0)
			(padstack
				(mode front_inner_back)
				(layer "Inner"
					(shape circle)
					(size 1.5494 1.5494)
					(clearance 0)
				)
				(layer "B.Cu"
					(shape rect)
					(size 1.5494 1.5494)
					(clearance 0)
				)
			)
		)
		(pad "2" thru_hole circle
			(at 0 2.54)
			(size 1.5494 1.5494)
			(drill 1.0414)
			(layers "*.Cu" "*.Mask")
			(remove_unused_layers no)
			(net "GND")
			(clearance 0)
		)
		(pad "3" thru_hole circle
			(at 0 5.08)
			(size 1.5494 1.5494)
			(drill 1.0414)
			(layers "*.Cu" "*.Mask")
			(remove_unused_layers no)
			(net "SMB_SML1_PMBUS_3V3AUX_PCH_SDA_1")
			(clearance 0)
		)
	)
	(footprint ""
		(layer "F.Cu")
		(at 300.6852 -28.3464 180)
		(property "Reference" "R1203"
			(at 0 0 180)
			(layer "F.SilkS")
			(hide yes)
			(effects
				(font
					(size 1.27 1.27)
				)
			)
		)
		(property "Value" ""
			(at 0 0 180)
			(layer "F.Fab")
			(effects
				(font
					(size 1.27 1.27)
				)
			)
		)
		(duplicate_pad_numbers_are_jumpers no)
		(fp_line
			(start 0.7874 0.4064)
			(end -0.7874 0.4064)
			(stroke
				(width 0.1524)
				(type default)
			)
			(layer "F.SilkS")
		)
		(fp_line
			(start 0.7874 -0.4064)
			(end 0.7874 0.4064)
			(stroke
				(width 0.1524)
				(type default)
			)
			(layer "F.SilkS")
		)
		(fp_line
			(start -0.7874 0.4064)
			(end -0.7874 -0.4064)
			(stroke
				(width 0.1524)
				(type default)
			)
			(layer "F.SilkS")
		)
		(fp_line
			(start -0.7874 -0.4064)
			(end 0.7874 -0.4064)
			(stroke
				(width 0.1524)
				(type default)
			)
			(layer "F.SilkS")
		)
		(fp_line
			(start 0.67945 0.3048)
			(end 0.120396 0.3048)
			(stroke
				(width 0.1)
				(type default)
			)
			(layer "F.Fab")
		)
		(fp_line
			(start 0.67945 -0.3048)
			(end 0.67945 0.3048)
			(stroke
				(width 0.1)
				(type default)
			)
			(layer "F.Fab")
		)
		(fp_line
			(start 0.12065 -0.2794)
			(end 0.12065 -0.3048)
			(stroke
				(width 0.1)
				(type default)
			)
			(layer "F.Fab")
		)
		(fp_line
			(start 0.12065 -0.3048)
			(end 0.67945 -0.3048)
			(stroke
				(width 0.1)
				(type default)
			)
			(layer "F.Fab")
		)
		(fp_line
			(start 0.120396 0.3048)
			(end 0.120396 0.2794)
			(stroke
				(width 0.1)
				(type default)
			)
			(layer "F.Fab")
		)
		(fp_line
			(start 0.120396 0.2794)
			(end -0.12065 0.2794)
			(stroke
				(width 0.1)
				(type default)
			)
			(layer "F.Fab")
		)
		(fp_line
			(start -0.12065 0.3048)
			(end -0.67945 0.3048)
			(stroke
				(width 0.1)
				(type default)
			)
			(layer "F.Fab")
		)
		(fp_line
			(start -0.12065 0.2794)
			(end -0.12065 0.3048)
			(stroke
				(width 0.1)
				(type default)
			)
			(layer "F.Fab")
		)
		(fp_line
			(start -0.12065 -0.2794)
			(end 0.12065 -0.2794)
			(stroke
				(width 0.1)
				(type default)
			)
			(layer "F.Fab")
		)
		(fp_line
			(start -0.12065 -0.305054)
			(end -0.12065 -0.2794)
			(stroke
				(width 0.1)
				(type default)
			)
			(layer "F.Fab")
		)
		(fp_line
			(start -0.67945 0.3048)
			(end -0.67945 -0.305054)
			(stroke
				(width 0.1)
				(type default)
			)
			(layer "F.Fab")
		)
		(fp_line
			(start -0.67945 -0.305054)
			(end -0.12065 -0.305054)
			(stroke
				(width 0.1)
				(type default)
			)
			(layer "F.Fab")
		)
		(pad "1" smd circle
			(at -0.40005 0 180)
			(size 0 0)
			(layers "F.Cu" "F.Mask" "F.Paste")
			(net "P3V_BAT")
		)
		(pad "2" smd circle
			(at 0.40005 0 180)
			(size 0 0)
			(layers "F.Cu" "F.Mask" "F.Paste")
			(net "P3V_BAT_R")
		)
	)
)
